(kicad_pcb
	(version 20260206)
	(generator "pcbnew")
	(generator_version "10.0")
	(general
		(thickness 1.6)
		(legacy_teardrops no)
	)
	(paper "A4")
	(title_block
		(title "v1-chassis-manager — T6M_CM_d_v01_1031_1645.brd")
		(comment 1 "Open CloudServer (Microsoft) / footprints 2343-2353 of 2512")
	)
	(layers
		(0 "F.Cu" signal "TOP")
		(4 "In1.Cu" signal "GND1")
		(6 "In2.Cu" signal "IN1")
		(8 "In3.Cu" signal "VCC1")
		(10 "In4.Cu" signal "VCC2")
		(12 "In5.Cu" signal "GND2")
		(14 "In6.Cu" signal "IN2")
		(16 "In7.Cu" signal "IN3")
		(18 "In8.Cu" signal "GND3")
		(2 "B.Cu" signal "BOTTOM")
		(9 "F.Adhes" user "F.Adhesive")
		(11 "B.Adhes" user "B.Adhesive")
		(13 "F.Paste" user "Package Geometry/Pastemask Top")
		(15 "B.Paste" user "Package Geometry/Pastemask Bottom")
		(5 "F.SilkS" user "Ref Des/Silkscreen Top")
		(7 "B.SilkS" user "Ref Des/Silkscreen Bottom")
		(1 "F.Mask" user "Board Geometry/Soldermask Top")
		(3 "B.Mask" user "Board Geometry/Soldermask Bottom")
		(17 "Dwgs.User" user "User.Drawings")
		(19 "Cmts.User" user "User.Comments")
		(21 "Eco1.User" user "User.Eco1")
		(23 "Eco2.User" user "User.Eco2")
		(25 "Edge.Cuts" user "Board Geometry/Outline")
		(27 "Margin" user)
		(31 "F.CrtYd" user "Package Geometry/Place Bound Top")
		(29 "B.CrtYd" user "Package Geometry/Place Bound Bottom")
		(35 "F.Fab" user "Ref Des/Assembly Top")
		(33 "B.Fab" user "Ref Des/Assembly Bottom")
	)
	(footprint ""
		(layer "B.Cu")
		(at 167.68318 -156.093922)
		(property "Reference" "C458"
			(at 5.988558 -0.052832 0)
			(unlocked yes)
			(layer "B.SilkS")
			(effects
				(font
					(size 0.7874 0.5842)
					(thickness 0.1524)
				)
				(justify left mirror)
			)
		)
		(property "Value" ""
			(at 0 0 0)
			(layer "B.Fab")
			(effects
				(font
					(size 1.27 1.27)
				)
				(justify mirror)
			)
		)
		(duplicate_pad_numbers_are_jumpers no)
		(fp_line
			(start -0.7874 -0.4064)
			(end -0.7874 0.4064)
			(stroke
				(width 0.1524)
				(type default)
			)
			(layer "B.SilkS")
		)
		(fp_line
			(start -0.7874 0.4064)
			(end 0.7874 0.4064)
			(stroke
				(width 0.1524)
				(type default)
			)
			(layer "B.SilkS")
		)
		(fp_line
			(start 0 0.381)
			(end 0 -0.381)
			(stroke
				(width 0.1524)
				(type default)
			)
			(layer "B.SilkS")
		)
		(fp_line
			(start 0.7874 -0.4064)
			(end -0.7874 -0.4064)
			(stroke
				(width 0.1524)
				(type default)
			)
			(layer "B.SilkS")
		)
		(fp_line
			(start 0.7874 0.4064)
			(end 0.7874 -0.4064)
			(stroke
				(width 0.1524)
				(type default)
			)
			(layer "B.SilkS")
		)
		(fp_poly
			(pts
				(xy 0.5334 0.254) (xy 0.635 0.254) (xy 0.635 0.2286) (xy 0.635 -0.254) (xy 0.5334 -0.254) (xy 0.5334 -0.2794)
				(xy -0.5334 -0.2794) (xy -0.5334 -0.254) (xy -0.635 -0.254) (xy -0.635 0.254) (xy -0.5334 0.254)
				(xy -0.5334 0.2794) (xy 0.508 0.2794) (xy 0.5334 0.2794)
			)
			(stroke
				(width 0)
				(type default)
			)
			(fill no)
			(layer "B.CrtYd")
		)
		(pad "1" smd rect
			(at -0.40005 0 180)
			(size 0.4572 0.508)
			(layers "B.Cu" "B.Mask" "B.Paste")
			(net "P1V9_LAN2")
		)
		(pad "2" smd rect
			(at 0.40005 0 180)
			(size 0.4572 0.508)
			(layers "B.Cu" "B.Mask" "B.Paste")
			(net "GND")
		)
	)
	(footprint ""
		(layer "B.Cu")
		(at 122.60453 -33.627314 180)
		(property "Reference" "C488"
			(at 2.543556 -1.50241 0)
			(unlocked yes)
			(layer "B.SilkS")
			(effects
				(font
					(size 0.7874 0.5842)
					(thickness 0.1524)
				)
				(justify left mirror)
			)
		)
		(property "Value" ""
			(at 0 0 0)
			(layer "B.Fab")
			(effects
				(font
					(size 1.27 1.27)
				)
				(justify mirror)
			)
		)
		(duplicate_pad_numbers_are_jumpers no)
		(fp_line
			(start 1.905 0.8636)
			(end 1.905 -0.8636)
			(stroke
				(width 0.1524)
				(type default)
			)
			(layer "B.SilkS")
		)
		(fp_line
			(start 1.905 -0.8636)
			(end -1.905 -0.8636)
			(stroke
				(width 0.1524)
				(type default)
			)
			(layer "B.SilkS")
		)
		(fp_line
			(start 0 0.8382)
			(end 0 -0.8382)
			(stroke
				(width 0.1524)
				(type default)
			)
			(layer "B.SilkS")
		)
		(fp_line
			(start -1.905 0.8636)
			(end 1.905 0.8636)
			(stroke
				(width 0.1524)
				(type default)
			)
			(layer "B.SilkS")
		)
		(fp_line
			(start -1.905 -0.8636)
			(end -1.905 0.8636)
			(stroke
				(width 0.1524)
				(type default)
			)
			(layer "B.SilkS")
		)
		(fp_rect
			(start 1.524 0.7366)
			(end -1.524 -0.7366)
			(stroke
				(width 0)
				(type default)
			)
			(fill no)
			(layer "B.CrtYd")
		)
		(pad "1" smd rect
			(at -0.94996 0)
			(size 1.1176 1.3716)
			(layers "B.Cu" "B.Mask" "B.Paste")
			(net "SIO_VCCH")
		)
		(pad "2" smd rect
			(at 0.94996 0)
			(size 1.1176 1.3716)
			(layers "B.Cu" "B.Mask" "B.Paste")
			(net "GND")
		)
	)
	(footprint ""
		(layer "B.Cu")
		(at 119.126 -35.941 -90)
		(property "Reference" "R1291"
			(at 1.651 5.23367 270)
			(unlocked yes)
			(layer "B.SilkS")
			(effects
				(font
					(size 0.7874 0.5842)
					(thickness 0.1524)
				)
				(justify left mirror)
			)
		)
		(property "Value" ""
			(at 0 0 90)
			(layer "B.Fab")
			(effects
				(font
					(size 1.27 1.27)
				)
				(justify mirror)
			)
		)
		(duplicate_pad_numbers_are_jumpers no)
		(fp_line
			(start -0.7874 0.4064)
			(end 0.7874 0.4064)
			(stroke
				(width 0.1524)
				(type default)
			)
			(layer "B.SilkS")
		)
		(fp_line
			(start 0.7874 0.4064)
			(end 0.7874 -0.4064)
			(stroke
				(width 0.1524)
				(type default)
			)
			(layer "B.SilkS")
		)
		(fp_line
			(start -0.7874 -0.4064)
			(end -0.7874 0.4064)
			(stroke
				(width 0.1524)
				(type default)
			)
			(layer "B.SilkS")
		)
		(fp_line
			(start 0.7874 -0.4064)
			(end -0.7874 -0.4064)
			(stroke
				(width 0.1524)
				(type default)
			)
			(layer "B.SilkS")
		)
		(fp_poly
			(pts
				(xy 0.508 0.2794) (xy 0.508 0.2286) (xy 0.635 0.2286) (xy 0.635 -0.254) (xy 0.5334 -0.254) (xy 0.5334 -0.2794)
				(xy -0.5334 -0.2794) (xy -0.5334 -0.254) (xy -0.635 -0.254) (xy -0.635 0.254) (xy -0.5334 0.254)
				(xy -0.5334 0.2794)
			)
			(stroke
				(width 0)
				(type default)
			)
			(fill no)
			(layer "B.CrtYd")
		)
		(pad "1" smd rect
			(at -0.40005 0 90)
			(size 0.4572 0.508)
			(layers "B.Cu" "B.Mask" "B.Paste")
			(net "SIO_JTAG_CPLD1_TCK_R")
		)
		(pad "2" smd rect
			(at 0.40005 0 90)
			(size 0.4572 0.508)
			(layers "B.Cu" "B.Mask" "B.Paste")
			(net "P3V3_NODE1")
		)
	)
	(footprint ""
		(layer "B.Cu")
		(at 42.113962 -163.52647 90)
		(property "Reference" "TP1"
			(at 0 0 90)
			(layer "B.SilkS")
			(hide yes)
			(effects
				(font
					(size 1.27 1.27)
				)
				(justify mirror)
			)
		)
		(property "Value" ""
			(at 0 0 90)
			(layer "B.Fab")
			(effects
				(font
					(size 1.27 1.27)
				)
				(justify mirror)
			)
		)
		(duplicate_pad_numbers_are_jumpers no)
		(fp_poly
			(pts
				(arc
					(start 0 -0.381)
					(mid 0 0.381)
					(end 0 -0.381)
				)
			)
			(stroke
				(width 0)
				(type default)
			)
			(fill no)
			(layer "B.CrtYd")
		)
		(pad "1" smd circle
			(at 0 0 270)
			(size 0.762 0.762)
			(layers "B.Cu" "B.Mask" "B.Paste")
			(net "N21311590")
		)
	)
	(footprint ""
		(layer "B.Cu")
		(at 52.81676 -188.126624 -90)
		(property "Reference" "R853"
			(at -4.339082 -0.278384 270)
			(unlocked yes)
			(layer "B.SilkS")
			(effects
				(font
					(size 0.7874 0.5842)
					(thickness 0.1524)
				)
				(justify left mirror)
			)
		)
		(property "Value" ""
			(at 0 0 90)
			(layer "B.Fab")
			(effects
				(font
					(size 1.27 1.27)
				)
				(justify mirror)
			)
		)
		(duplicate_pad_numbers_are_jumpers no)
		(fp_line
			(start -0.7874 0.4064)
			(end 0.7874 0.4064)
			(stroke
				(width 0.1524)
				(type default)
			)
			(layer "B.SilkS")
		)
		(fp_line
			(start 0.7874 0.4064)
			(end 0.7874 -0.4064)
			(stroke
				(width 0.1524)
				(type default)
			)
			(layer "B.SilkS")
		)
		(fp_line
			(start -0.7874 -0.4064)
			(end -0.7874 0.4064)
			(stroke
				(width 0.1524)
				(type default)
			)
			(layer "B.SilkS")
		)
		(fp_line
			(start 0.7874 -0.4064)
			(end -0.7874 -0.4064)
			(stroke
				(width 0.1524)
				(type default)
			)
			(layer "B.SilkS")
		)
		(fp_poly
			(pts
				(xy 0.508 0.2794) (xy 0.508 0.2286) (xy 0.635 0.2286) (xy 0.635 -0.254) (xy 0.5334 -0.254) (xy 0.5334 -0.2794)
				(xy -0.5334 -0.2794) (xy -0.5334 -0.254) (xy -0.635 -0.254) (xy -0.635 0.254) (xy -0.5334 0.254)
				(xy -0.5334 0.2794)
			)
			(stroke
				(width 0)
				(type default)
			)
			(fill no)
			(layer "B.CrtYd")
		)
		(pad "1" smd rect
			(at -0.40005 0 90)
			(size 0.4572 0.508)
			(layers "B.Cu" "B.Mask" "B.Paste")
			(net "PSU1_DC_OK_R")
		)
		(pad "2" smd rect
			(at 0.40005 0 90)
			(size 0.4572 0.508)
			(layers "B.Cu" "B.Mask" "B.Paste")
			(net "GND")
		)
	)
	(footprint ""
		(layer "B.Cu")
		(at 109.58576 -188.126624 90)
		(property "Reference" "R973"
			(at 4.080256 0.645922 270)
			(unlocked yes)
			(layer "B.SilkS")
			(effects
				(font
					(size 0.7874 0.5842)
					(thickness 0.1524)
				)
				(justify left mirror)
			)
		)
		(property "Value" ""
			(at 0 0 90)
			(layer "B.Fab")
			(effects
				(font
					(size 1.27 1.27)
				)
				(justify mirror)
			)
		)
		(duplicate_pad_numbers_are_jumpers no)
		(fp_line
			(start 0.7874 -0.4064)
			(end -0.7874 -0.4064)
			(stroke
				(width 0.1524)
				(type default)
			)
			(layer "B.SilkS")
		)
		(fp_line
			(start -0.7874 -0.4064)
			(end -0.7874 0.4064)
			(stroke
				(width 0.1524)
				(type default)
			)
			(layer "B.SilkS")
		)
		(fp_line
			(start 0.7874 0.4064)
			(end 0.7874 -0.4064)
			(stroke
				(width 0.1524)
				(type default)
			)
			(layer "B.SilkS")
		)
		(fp_line
			(start -0.7874 0.4064)
			(end 0.7874 0.4064)
			(stroke
				(width 0.1524)
				(type default)
			)
			(layer "B.SilkS")
		)
		(fp_poly
			(pts
				(xy 0.508 0.2794) (xy 0.508 0.2286) (xy 0.635 0.2286) (xy 0.635 -0.254) (xy 0.5334 -0.254) (xy 0.5334 -0.2794)
				(xy -0.5334 -0.2794) (xy -0.5334 -0.254) (xy -0.635 -0.254) (xy -0.635 0.254) (xy -0.5334 0.254)
				(xy -0.5334 0.2794)
			)
			(stroke
				(width 0)
				(type default)
			)
			(fill no)
			(layer "B.CrtYd")
		)
		(pad "1" smd rect
			(at -0.40005 0 270)
			(size 0.4572 0.508)
			(layers "B.Cu" "B.Mask" "B.Paste")
			(net "UART_T7_NODE4_RXD")
		)
		(pad "2" smd rect
			(at 0.40005 0 270)
			(size 0.4572 0.508)
			(layers "B.Cu" "B.Mask" "B.Paste")
			(net "UART_T7_NODE4_RXD_R")
		)
	)
	(footprint ""
		(layer "B.Cu")
		(at 172.84573 -118.87962 180)
		(property "Reference" "C792"
			(at 2.503678 -1.906778 0)
			(unlocked yes)
			(layer "B.SilkS")
			(effects
				(font
					(size 0.7874 0.5842)
					(thickness 0.1524)
				)
				(justify mirror)
			)
		)
		(property "Value" ""
			(at 0 0 0)
			(layer "B.Fab")
			(effects
				(font
					(size 1.27 1.27)
				)
				(justify mirror)
			)
		)
		(duplicate_pad_numbers_are_jumpers no)
		(fp_line
			(start 1.2954 0.5842)
			(end 1.2954 -0.5842)
			(stroke
				(width 0.1524)
				(type default)
			)
			(layer "B.SilkS")
		)
		(fp_line
			(start 1.2954 -0.5842)
			(end -1.2954 -0.5842)
			(stroke
				(width 0.1524)
				(type default)
			)
			(layer "B.SilkS")
		)
		(fp_line
			(start 0 -0.5842)
			(end 0 0.5842)
			(stroke
				(width 0.1524)
				(type default)
			)
			(layer "B.SilkS")
		)
		(fp_line
			(start -1.2954 0.5842)
			(end 1.2954 0.5842)
			(stroke
				(width 0.1524)
				(type default)
			)
			(layer "B.SilkS")
		)
		(fp_line
			(start -1.2954 -0.5842)
			(end -1.2954 0.5842)
			(stroke
				(width 0.1524)
				(type default)
			)
			(layer "B.SilkS")
		)
		(fp_poly
			(pts
				(xy -0.8636 -0.4572) (xy -0.8636 -0.3556) (xy -1.143 -0.3556) (xy -1.143 0.3556) (xy -0.8636 0.3556)
				(xy -0.8636 0.4572) (xy 0.8636 0.4572) (xy 0.8636 0.3556) (xy 1.143 0.3556) (xy 1.143 -0.3556) (xy 0.8636 -0.3556)
				(xy 0.8636 -0.4572)
			)
			(stroke
				(width 0)
				(type default)
			)
			(fill no)
			(layer "B.CrtYd")
		)
		(fp_line
			(start 0.884936 0.504952)
			(end 0.884936 -0.504952)
			(stroke
				(width 0.1)
				(type default)
			)
			(layer "B.Fab")
		)
		(fp_line
			(start 0.884936 -0.504952)
			(end -0.884936 -0.504952)
			(stroke
				(width 0.1)
				(type default)
			)
			(layer "B.Fab")
		)
		(fp_line
			(start -0.884936 0.504952)
			(end 0.884936 0.504952)
			(stroke
				(width 0.1)
				(type default)
			)
			(layer "B.Fab")
		)
		(fp_line
			(start -0.884936 -0.504952)
			(end -0.884936 0.504952)
			(stroke
				(width 0.1)
				(type default)
			)
			(layer "B.Fab")
		)
		(pad "1" smd rect
			(at -0.7366 0 270)
			(size 0.7112 0.8128)
			(layers "B.Cu" "B.Mask" "B.Paste")
			(net "P3V3_STB_NODE1")
		)
		(pad "2" smd rect
			(at 0.7366 0 270)
			(size 0.7112 0.8128)
			(layers "B.Cu" "B.Mask" "B.Paste")
			(net "GND")
		)
	)
	(footprint ""
		(layer "B.Cu")
		(at 110.44936 -179.617624 180)
		(property "Reference" "R715"
			(at 21.356828 -32.269176 0)
			(unlocked yes)
			(layer "B.SilkS")
			(effects
				(font
					(size 0.7874 0.5842)
					(thickness 0.1524)
				)
				(justify left mirror)
			)
		)
		(property "Value" ""
			(at 0 0 0)
			(layer "B.Fab")
			(effects
				(font
					(size 1.27 1.27)
				)
				(justify mirror)
			)
		)
		(duplicate_pad_numbers_are_jumpers no)
		(fp_line
			(start 0.7874 0.4064)
			(end 0.7874 -0.4064)
			(stroke
				(width 0.1524)
				(type default)
			)
			(layer "B.SilkS")
		)
		(fp_line
			(start 0.7874 -0.4064)
			(end -0.7874 -0.4064)
			(stroke
				(width 0.1524)
				(type default)
			)
			(layer "B.SilkS")
		)
		(fp_line
			(start -0.7874 0.4064)
			(end 0.7874 0.4064)
			(stroke
				(width 0.1524)
				(type default)
			)
			(layer "B.SilkS")
		)
		(fp_line
			(start -0.7874 -0.4064)
			(end -0.7874 0.4064)
			(stroke
				(width 0.1524)
				(type default)
			)
			(layer "B.SilkS")
		)
		(fp_poly
			(pts
				(xy 0.508 0.2794) (xy 0.508 0.2286) (xy 0.635 0.2286) (xy 0.635 -0.254) (xy 0.5334 -0.254) (xy 0.5334 -0.2794)
				(xy -0.5334 -0.2794) (xy -0.5334 -0.254) (xy -0.635 -0.254) (xy -0.635 0.254) (xy -0.5334 0.254)
				(xy -0.5334 0.2794)
			)
			(stroke
				(width 0)
				(type default)
			)
			(fill no)
			(layer "B.CrtYd")
		)
		(pad "1" smd rect
			(at -0.40005 0)
			(size 0.4572 0.508)
			(layers "B.Cu" "B.Mask" "B.Paste")
			(net "T6_NODE2_EN")
		)
		(pad "2" smd rect
			(at 0.40005 0)
			(size 0.4572 0.508)
			(layers "B.Cu" "B.Mask" "B.Paste")
			(net "P5V_NODE1")
		)
	)
	(footprint ""
		(layer "B.Cu")
		(at 94.211394 -185.790586 180)
		(property "Reference" "R927"
			(at -1.315466 6.002782 0)
			(unlocked yes)
			(layer "B.SilkS")
			(effects
				(font
					(size 0.7874 0.5842)
					(thickness 0.1524)
				)
				(justify left mirror)
			)
		)
		(property "Value" ""
			(at 0 0 0)
			(layer "B.Fab")
			(effects
				(font
					(size 1.27 1.27)
				)
				(justify mirror)
			)
		)
		(duplicate_pad_numbers_are_jumpers no)
		(fp_line
			(start 0.7874 0.406146)
			(end 0.7874 -0.406146)
			(stroke
				(width 0.1524)
				(type default)
			)
			(layer "B.SilkS")
		)
		(fp_line
			(start 0.7874 -0.406146)
			(end -0.7874 -0.406146)
			(stroke
				(width 0.1524)
				(type default)
			)
			(layer "B.SilkS")
		)
		(fp_line
			(start -0.7874 0.406146)
			(end 0.7874 0.406146)
			(stroke
				(width 0.1524)
				(type default)
			)
			(layer "B.SilkS")
		)
		(fp_line
			(start -0.7874 -0.406146)
			(end -0.7874 0.406146)
			(stroke
				(width 0.1524)
				(type default)
			)
			(layer "B.SilkS")
		)
		(fp_poly
			(pts
				(xy 0.508 0.2794) (xy 0.508 0.2286) (xy 0.635 0.2286) (xy 0.635 -0.254) (xy 0.5334 -0.254) (xy 0.5334 -0.2794)
				(xy -0.5334 -0.2794) (xy -0.5334 -0.254) (xy -0.635 -0.254) (xy -0.635 0.254) (xy -0.5334 0.254)
				(xy -0.5334 0.2794)
			)
			(stroke
				(width 0)
				(type default)
			)
			(fill no)
			(layer "B.CrtYd")
		)
		(pad "1" smd rect
			(at -0.40005 0)
			(size 0.4572 0.508)
			(layers "B.Cu" "B.Mask" "B.Paste")
			(net "UART_T5_NODE4_RXD")
		)
		(pad "2" smd rect
			(at 0.40005 0)
			(size 0.4572 0.508)
			(layers "B.Cu" "B.Mask" "B.Paste")
			(net "UART_T5_NODE4_RXD_R")
		)
	)
	(footprint ""
		(layer "B.Cu")
		(at 95.740982 -29.925518)
		(property "Reference" "R206"
			(at 1.810766 1.08839 0)
			(unlocked yes)
			(layer "B.SilkS")
			(effects
				(font
					(size 0.7874 0.5842)
					(thickness 0.1524)
				)
				(justify left mirror)
			)
		)
		(property "Value" ""
			(at 0 0 0)
			(layer "B.Fab")
			(effects
				(font
					(size 1.27 1.27)
				)
				(justify mirror)
			)
		)
		(duplicate_pad_numbers_are_jumpers no)
		(fp_line
			(start -0.7874 -0.4064)
			(end -0.7874 0.4064)
			(stroke
				(width 0.1524)
				(type default)
			)
			(layer "B.SilkS")
		)
		(fp_line
			(start -0.7874 0.4064)
			(end 0.7874 0.4064)
			(stroke
				(width 0.1524)
				(type default)
			)
			(layer "B.SilkS")
		)
		(fp_line
			(start 0.7874 -0.4064)
			(end -0.7874 -0.4064)
			(stroke
				(width 0.1524)
				(type default)
			)
			(layer "B.SilkS")
		)
		(fp_line
			(start 0.7874 0.4064)
			(end 0.7874 -0.4064)
			(stroke
				(width 0.1524)
				(type default)
			)
			(layer "B.SilkS")
		)
		(fp_poly
			(pts
				(xy 0.508 0.2794) (xy 0.508 0.2286) (xy 0.635 0.2286) (xy 0.635 -0.254) (xy 0.5334 -0.254) (xy 0.5334 -0.2794)
				(xy -0.5334 -0.2794) (xy -0.5334 -0.254) (xy -0.635 -0.254) (xy -0.635 0.254) (xy -0.5334 0.254)
				(xy -0.5334 0.2794)
			)
			(stroke
				(width 0)
				(type default)
			)
			(fill no)
			(layer "B.CrtYd")
		)
		(pad "1" smd rect
			(at -0.40005 0 180)
			(size 0.4572 0.508)
			(layers "B.Cu" "B.Mask" "B.Paste")
			(net "GND")
		)
		(pad "2" smd rect
			(at 0.40005 0 180)
			(size 0.4572 0.508)
			(layers "B.Cu" "B.Mask" "B.Paste")
			(net "PD_NODE1_DM6")
		)
	)
	(footprint ""
		(layer "B.Cu")
		(at 44.609258 -60.445396 -90)
		(property "Reference" "C22"
			(at 2.31775 2.249424 270)
			(unlocked yes)
			(layer "B.SilkS")
			(effects
				(font
					(size 0.7874 0.5842)
					(thickness 0.1524)
				)
				(justify left mirror)
			)
		)
		(property "Value" ""
			(at 0 0 90)
			(layer "B.Fab")
			(effects
				(font
					(size 1.27 1.27)
				)
				(justify mirror)
			)
		)
		(duplicate_pad_numbers_are_jumpers no)
		(fp_line
			(start -0.7874 0.4064)
			(end 0.7874 0.4064)
			(stroke
				(width 0.1524)
				(type default)
			)
			(layer "B.SilkS")
		)
		(fp_line
			(start 0.7874 0.4064)
			(end 0.7874 -0.4064)
			(stroke
				(width 0.1524)
				(type default)
			)
			(layer "B.SilkS")
		)
		(fp_line
			(start 0 0.381)
			(end 0 -0.381)
			(stroke
				(width 0.1524)
				(type default)
			)
			(layer "B.SilkS")
		)
		(fp_line
			(start -0.7874 -0.4064)
			(end -0.7874 0.4064)
			(stroke
				(width 0.1524)
				(type default)
			)
			(layer "B.SilkS")
		)
		(fp_line
			(start 0.7874 -0.4064)
			(end -0.7874 -0.4064)
			(stroke
				(width 0.1524)
				(type default)
			)
			(layer "B.SilkS")
		)
		(fp_poly
			(pts
				(xy 0.5334 0.254) (xy 0.635 0.254) (xy 0.635 0.2286) (xy 0.635 -0.254) (xy 0.5334 -0.254) (xy 0.5334 -0.2794)
				(xy -0.5334 -0.2794) (xy -0.5334 -0.254) (xy -0.635 -0.254) (xy -0.635 0.254) (xy -0.5334 0.254)
				(xy -0.5334 0.2794) (xy 0.508 0.2794) (xy 0.5334 0.2794)
			)
			(stroke
				(width 0)
				(type default)
			)
			(fill no)
			(layer "B.CrtYd")
		)
		(pad "1" smd rect
			(at -0.40005 0 90)
			(size 0.4572 0.508)
			(layers "B.Cu" "B.Mask" "B.Paste")
			(net "P2E_CPU_SATA_NODE1_TX_C_DN")
		)
		(pad "2" smd rect
			(at 0.40005 0 90)
			(size 0.4572 0.508)
			(layers "B.Cu" "B.Mask" "B.Paste")
			(net "P2E_CPU_SATA_NODE1_TX_DN")
		)
	)
)
